(kicad_pcb
	(version 20260206)
	(generator "pcbnew")
	(generator_version "10.0")
	(general
		(thickness 1.6)
		(legacy_teardrops no)
	)
	(paper "A4")
	(title_block
		(title "netronome-mezz — pcbd0082-001_rev01_jul9_a.brd")
		(comment 1 "Open CloudServer (Microsoft) / footprints 703-712 of 714")
	)
	(layers
		(0 "F.Cu" signal "TOP")
		(4 "In1.Cu" signal "02_GND")
		(6 "In2.Cu" signal "03_SIG")
		(8 "In3.Cu" signal "04_SIG")
		(10 "In4.Cu" signal "05_GND")
		(12 "In5.Cu" signal "06_PWR1")
		(14 "In6.Cu" signal "07_SIG")
		(16 "In7.Cu" signal "08_SIG")
		(18 "In8.Cu" signal "09_GND")
		(2 "B.Cu" signal "BOTTOM")
		(9 "F.Adhes" user "F.Adhesive")
		(11 "B.Adhes" user "B.Adhesive")
		(13 "F.Paste" user "Package Geometry/Pastemask Top")
		(15 "B.Paste" user "Package Geometry/Pastemask Bottom")
		(5 "F.SilkS" user "Ref Des/Silkscreen Top")
		(7 "B.SilkS" user "Ref Des/Silkscreen Bottom")
		(1 "F.Mask" user "Board Geometry/Soldermask Top")
		(3 "B.Mask" user "Board Geometry/Soldermask Bottom")
		(17 "Dwgs.User" user "User.Drawings")
		(19 "Cmts.User" user "User.Comments")
		(21 "Eco1.User" user "User.Eco1")
		(23 "Eco2.User" user "User.Eco2")
		(25 "Edge.Cuts" user "Board Geometry/Outline")
		(27 "Margin" user)
		(31 "F.CrtYd" user "Package Geometry/Place Bound Top")
		(29 "B.CrtYd" user "Package Geometry/Place Bound Bottom")
		(35 "F.Fab" user "Ref Des/Assembly Top")
		(33 "B.Fab" user "Ref Des/Assembly Bottom")
		(45 "User.4" user "COMPVAL_TYPE_BOTTOM")
	)
	(footprint ""
		(layer "B.Cu")
		(at 84.250987 14.256004)
		(property "Reference" "V2_A-A13"
			(at 0 0 0)
			(layer "B.SilkS")
			(hide yes)
			(effects
				(font
					(size 1.27 1.27)
				)
				(justify mirror)
			)
		)
		(property "Value" ""
			(at 0 0 0)
			(layer "B.Fab")
			(effects
				(font
					(size 1.27 1.27)
				)
				(justify mirror)
			)
		)
		(duplicate_pad_numbers_are_jumpers no)
		(pad "1" thru_hole circle
			(at 0 0 180)
			(size 0.4572 0.4572)
			(drill 0.20574)
			(layers "*.Cu" "*.Mask")
			(remove_unused_layers no)
			(net "DDR0_32A_A13")
			(clearance 0.1143)
			(thermal_gap 0.1143)
		)
	)
	(footprint ""
		(layer "B.Cu")
		(at 27.432 32.639)
		(property "Reference" "R97"
			(at -0.28067 4.826 270)
			(unlocked yes)
			(layer "B.SilkS")
			(effects
				(font
					(size 0.7874 0.5842)
					(thickness 0.127)
				)
				(justify left mirror)
			)
		)
		(property "Value" "4.75K"
			(at 0.148158 1.3462 270)
			(unlocked yes)
			(layer "B.Fab")
			(hide yes)
			(effects
				(font
					(size 1.27 0.9652)
					(thickness 0.000001)
				)
				(justify left mirror)
			)
		)
		(property "Device Type" "REST4024"
			(at 0.148158 1.3462 270)
			(unlocked yes)
			(layer "B.Fab")
			(hide yes)
			(effects
				(font
					(size 1.27 0.9652)
					(thickness 0.000001)
				)
				(justify left mirror)
			)
		)
		(duplicate_pad_numbers_are_jumpers no)
		(fp_poly
			(pts
				(xy -0.635 1.0668) (xy -0.635 -1.0668) (xy 0.635 -1.0668) (xy 0.635 1.0668)
			)
			(stroke
				(width 0)
				(type default)
			)
			(fill no)
			(layer "B.CrtYd")
		)
		(fp_line
			(start -0.254 -0.508)
			(end -0.254 0.508)
			(stroke
				(width 0.0254)
				(type default)
			)
			(layer "B.Fab")
		)
		(fp_line
			(start -0.254 0.508)
			(end 0.254 0.508)
			(stroke
				(width 0.0254)
				(type default)
			)
			(layer "B.Fab")
		)
		(fp_line
			(start 0.254 -0.508)
			(end -0.254 -0.508)
			(stroke
				(width 0.0254)
				(type default)
			)
			(layer "B.Fab")
		)
		(fp_line
			(start 0.254 0.508)
			(end 0.254 -0.508)
			(stroke
				(width 0.0254)
				(type default)
			)
			(layer "B.Fab")
		)
		(pad "1" smd rect
			(at 0 -0.4191 180)
			(size 0.508 0.5334)
			(layers "B.Cu" "B.Mask" "B.Paste")
			(net "GND")
		)
		(pad "2" smd rect
			(at 0 0.4191 180)
			(size 0.508 0.5334)
			(layers "B.Cu" "B.Mask" "B.Paste")
			(net "_NFP_CORE_VID1")
		)
		(zone
			(layer "B.Cu")
			(hatch none 0.5)
			(connect_pads
				(clearance 0)
			)
			(min_thickness 0.25)
			(keepout
				(tracks not_allowed)
				(vias allowed)
				(pads allowed)
				(copperpour not_allowed)
				(footprints allowed)
			)
			(placement
				(enabled no)
				(sheetname "")
			)
			(fill
				(thermal_gap 0.5)
				(thermal_bridge_width 0.5)
				(island_removal_mode 0)
			)
			(polygon
				(pts
					(xy 27.4066 32.6136) (xy 27.4066 32.6644) (xy 27.4574 32.6644) (xy 27.4574 32.6136)
				)
			)
		)
	)
	(footprint ""
		(layer "B.Cu")
		(at 77.051002 18.255996)
		(property "Reference" "V_A-DQ23"
			(at 0 0 0)
			(layer "B.SilkS")
			(hide yes)
			(effects
				(font
					(size 1.27 1.27)
				)
				(justify mirror)
			)
		)
		(property "Value" ""
			(at 0 0 0)
			(layer "B.Fab")
			(effects
				(font
					(size 1.27 1.27)
				)
				(justify mirror)
			)
		)
		(duplicate_pad_numbers_are_jumpers no)
		(pad "1" thru_hole circle
			(at 0 0 180)
			(size 0.4572 0.4572)
			(drill 0.20574)
			(layers "*.Cu" "*.Mask")
			(remove_unused_layers no)
			(net "DDR0_32A_DQ23")
			(clearance 0.1143)
			(thermal_gap 0.1143)
		)
	)
	(footprint ""
		(layer "B.Cu")
		(at 53.4289 40.386 90)
		(property "Reference" "C180"
			(at -7.239 -0.87757 270)
			(unlocked yes)
			(layer "B.SilkS")
			(effects
				(font
					(size 0.7874 0.5842)
					(thickness 0.127)
				)
				(justify left mirror)
			)
		)
		(property "Value" ""
			(at 0 0 90)
			(layer "B.Fab")
			(effects
				(font
					(size 1.27 1.27)
				)
				(justify mirror)
			)
		)
		(duplicate_pad_numbers_are_jumpers no)
		(fp_circle
			(center 0 0)
			(end 0 0.508)
			(stroke
				(width 0.2032)
				(type default)
			)
			(fill no)
			(layer "B.SilkS")
		)
		(fp_poly
			(pts
				(xy 2.286 1.778) (xy 2.286 -1.778) (xy -2.286 -1.778) (xy -2.286 1.778)
			)
			(stroke
				(width 0)
				(type default)
			)
			(fill no)
			(layer "B.CrtYd")
		)
		(fp_line
			(start 1.524 -1.27)
			(end -1.524 -1.27)
			(stroke
				(width 0.0254)
				(type default)
			)
			(layer "B.Fab")
		)
		(fp_line
			(start -1.524 -1.27)
			(end -1.524 1.27)
			(stroke
				(width 0.0254)
				(type default)
			)
			(layer "B.Fab")
		)
		(fp_line
			(start 1.524 1.27)
			(end 1.524 -1.27)
			(stroke
				(width 0.0254)
				(type default)
			)
			(layer "B.Fab")
		)
		(fp_line
			(start -1.524 1.27)
			(end 1.524 1.27)
			(stroke
				(width 0.0254)
				(type default)
			)
			(layer "B.Fab")
		)
		(pad "1" smd rect
			(at 1.4224 0 180)
			(size 2.7432 1.3716)
			(layers "B.Cu" "B.Mask" "B.Paste")
			(net "EXT_12.0V")
		)
		(pad "2" smd rect
			(at -1.4224 0 180)
			(size 2.7432 1.3716)
			(layers "B.Cu" "B.Mask" "B.Paste")
			(net "GND")
		)
	)
	(footprint ""
		(layer "B.Cu")
		(at 45.3009 35.687)
		(property "Reference" "R74"
			(at 0 0 0)
			(layer "B.SilkS")
			(hide yes)
			(effects
				(font
					(size 1.27 1.27)
				)
				(justify mirror)
			)
		)
		(property "Value" "4.75K"
			(at 0.148158 1.3462 270)
			(unlocked yes)
			(layer "B.Fab")
			(hide yes)
			(effects
				(font
					(size 1.27 0.9652)
					(thickness 0.000001)
				)
				(justify left mirror)
			)
		)
		(property "Device Type" "REST4024"
			(at 0.148158 1.3462 270)
			(unlocked yes)
			(layer "B.Fab")
			(hide yes)
			(effects
				(font
					(size 1.27 0.9652)
					(thickness 0.000001)
				)
				(justify left mirror)
			)
		)
		(duplicate_pad_numbers_are_jumpers no)
		(fp_poly
			(pts
				(xy -0.635 1.0668) (xy -0.635 -1.0668) (xy 0.635 -1.0668) (xy 0.635 1.0668)
			)
			(stroke
				(width 0)
				(type default)
			)
			(fill no)
			(layer "B.CrtYd")
		)
		(fp_line
			(start -0.254 -0.508)
			(end -0.254 0.508)
			(stroke
				(width 0.0254)
				(type default)
			)
			(layer "B.Fab")
		)
		(fp_line
			(start -0.254 0.508)
			(end 0.254 0.508)
			(stroke
				(width 0.0254)
				(type default)
			)
			(layer "B.Fab")
		)
		(fp_line
			(start 0.254 -0.508)
			(end -0.254 -0.508)
			(stroke
				(width 0.0254)
				(type default)
			)
			(layer "B.Fab")
		)
		(fp_line
			(start 0.254 0.508)
			(end 0.254 -0.508)
			(stroke
				(width 0.0254)
				(type default)
			)
			(layer "B.Fab")
		)
		(pad "1" smd rect
			(at 0 -0.4191 180)
			(size 0.508 0.5334)
			(layers "B.Cu" "B.Mask" "B.Paste")
			(net "VDD_5.0V")
		)
		(pad "2" smd rect
			(at 0 0.4191 180)
			(size 0.508 0.5334)
			(layers "B.Cu" "B.Mask" "B.Paste")
			(net "10N2256")
		)
		(zone
			(layer "B.Cu")
			(hatch none 0.5)
			(connect_pads
				(clearance 0)
			)
			(min_thickness 0.25)
			(keepout
				(tracks not_allowed)
				(vias allowed)
				(pads allowed)
				(copperpour not_allowed)
				(footprints allowed)
			)
			(placement
				(enabled no)
				(sheetname "")
			)
			(fill
				(thermal_gap 0.5)
				(thermal_bridge_width 0.5)
				(island_removal_mode 0)
			)
			(polygon
				(pts
					(xy 45.2755 35.6616) (xy 45.2755 35.7124) (xy 45.3263 35.7124) (xy 45.3263 35.6616)
				)
			)
		)
	)
	(footprint ""
		(layer "B.Cu")
		(at 23.876 4.699 180)
		(property "Reference" "R369"
			(at 0.254 -1.04267 0)
			(unlocked yes)
			(layer "B.SilkS")
			(effects
				(font
					(size 0.7874 0.5842)
					(thickness 0.127)
				)
				(justify left mirror)
			)
		)
		(property "Value" "4.75K"
			(at 0.148158 1.3462 90)
			(unlocked yes)
			(layer "B.Fab")
			(hide yes)
			(effects
				(font
					(size 1.27 0.9652)
					(thickness 0.000001)
				)
				(justify left mirror)
			)
		)
		(property "Device Type" "REST4024"
			(at 0.148158 1.3462 90)
			(unlocked yes)
			(layer "B.Fab")
			(hide yes)
			(effects
				(font
					(size 1.27 0.9652)
					(thickness 0.000001)
				)
				(justify left mirror)
			)
		)
		(duplicate_pad_numbers_are_jumpers no)
		(fp_poly
			(pts
				(xy -0.635 1.0668) (xy -0.635 -1.0668) (xy 0.635 -1.0668) (xy 0.635 1.0668)
			)
			(stroke
				(width 0)
				(type default)
			)
			(fill no)
			(layer "B.CrtYd")
		)
		(fp_line
			(start 0.254 0.508)
			(end 0.254 -0.508)
			(stroke
				(width 0.0254)
				(type default)
			)
			(layer "B.Fab")
		)
		(fp_line
			(start 0.254 -0.508)
			(end -0.254 -0.508)
			(stroke
				(width 0.0254)
				(type default)
			)
			(layer "B.Fab")
		)
		(fp_line
			(start -0.254 0.508)
			(end 0.254 0.508)
			(stroke
				(width 0.0254)
				(type default)
			)
			(layer "B.Fab")
		)
		(fp_line
			(start -0.254 -0.508)
			(end -0.254 0.508)
			(stroke
				(width 0.0254)
				(type default)
			)
			(layer "B.Fab")
		)
		(pad "1" smd rect
			(at 0 -0.4191)
			(size 0.508 0.5334)
			(layers "B.Cu" "B.Mask" "B.Paste")
			(net "NFP_SMBUS_SDA")
		)
		(pad "2" smd rect
			(at 0 0.4191)
			(size 0.508 0.5334)
			(layers "B.Cu" "B.Mask" "B.Paste")
			(net "EXT_3.3V")
		)
		(zone
			(layer "B.Cu")
			(hatch none 0.5)
			(connect_pads
				(clearance 0)
			)
			(min_thickness 0.25)
			(keepout
				(tracks not_allowed)
				(vias allowed)
				(pads allowed)
				(copperpour not_allowed)
				(footprints allowed)
			)
			(placement
				(enabled no)
				(sheetname "")
			)
			(fill
				(thermal_gap 0.5)
				(thermal_bridge_width 0.5)
				(island_removal_mode 0)
			)
			(polygon
				(pts
					(xy 23.9014 4.7244) (xy 23.9014 4.6736) (xy 23.8506 4.6736) (xy 23.8506 4.7244)
				)
			)
		)
	)
	(footprint ""
		(layer "B.Cu")
		(at 74.168 35.052 90)
		(property "Reference" "R119"
			(at 0.10033 4.572 0)
			(unlocked yes)
			(layer "B.SilkS")
			(effects
				(font
					(size 0.7874 0.5842)
					(thickness 0.127)
				)
				(justify left mirror)
			)
		)
		(property "Value" "2.2"
			(at 0.148158 1.7526 0)
			(unlocked yes)
			(layer "B.Fab")
			(hide yes)
			(effects
				(font
					(size 1.27 0.9652)
					(thickness 0.000001)
				)
				(justify left mirror)
			)
		)
		(property "Device Type" "REST0145"
			(at 0.148158 1.7526 0)
			(unlocked yes)
			(layer "B.Fab")
			(hide yes)
			(effects
				(font
					(size 1.27 0.9652)
					(thickness 0.000001)
				)
				(justify left mirror)
			)
		)
		(duplicate_pad_numbers_are_jumpers no)
		(fp_circle
			(center 0 0)
			(end 0 0.127)
			(stroke
				(width 0.2032)
				(type default)
			)
			(fill no)
			(layer "B.SilkS")
		)
		(fp_poly
			(pts
				(xy -0.7874 -1.6637) (xy 0.7874 -1.6637) (xy 0.7874 1.6637) (xy -0.7874 1.6637)
			)
			(stroke
				(width 0)
				(type default)
			)
			(fill no)
			(layer "B.CrtYd")
		)
		(fp_line
			(start 0.4064 -0.8128)
			(end -0.4064 -0.8128)
			(stroke
				(width 0.0254)
				(type default)
			)
			(layer "B.Fab")
		)
		(fp_line
			(start -0.4064 -0.8128)
			(end -0.4064 0.8128)
			(stroke
				(width 0.0254)
				(type default)
			)
			(layer "B.Fab")
		)
		(fp_line
			(start 0.4064 0.8128)
			(end 0.4064 -0.8128)
			(stroke
				(width 0.0254)
				(type default)
			)
			(layer "B.Fab")
		)
		(fp_line
			(start -0.4064 0.8128)
			(end 0.4064 0.8128)
			(stroke
				(width 0.0254)
				(type default)
			)
			(layer "B.Fab")
		)
		(pad "1" smd rect
			(at 0 -0.8001 270)
			(size 0.762 0.9652)
			(layers "B.Cu" "B.Mask" "B.Paste")
			(net "10N2228")
		)
		(pad "2" smd rect
			(at 0 0.8001 270)
			(size 0.762 0.9652)
			(layers "B.Cu" "B.Mask" "B.Paste")
			(net "10N2262")
		)
		(zone
			(layer "B.Cu")
			(hatch none 0.5)
			(connect_pads
				(clearance 0)
			)
			(min_thickness 0.25)
			(keepout
				(tracks not_allowed)
				(vias allowed)
				(pads allowed)
				(copperpour not_allowed)
				(footprints allowed)
			)
			(placement
				(enabled no)
				(sheetname "")
			)
			(fill
				(thermal_gap 0.5)
				(thermal_bridge_width 0.5)
				(island_removal_mode 0)
			)
			(polygon
				(pts
					(xy 73.914 34.9885) (xy 73.914 35.1155) (xy 74.422 35.1155) (xy 74.422 34.9885)
				)
			)
		)
	)
	(footprint ""
		(layer "B.Cu")
		(at 0.6096 17.4498)
		(property "Reference" "R373"
			(at -1.01727 2.3622 270)
			(unlocked yes)
			(layer "B.SilkS")
			(effects
				(font
					(size 0.7874 0.5842)
					(thickness 0.127)
				)
				(justify left mirror)
			)
		)
		(property "Value" "4.75K"
			(at 0.148158 1.3462 270)
			(unlocked yes)
			(layer "B.Fab")
			(hide yes)
			(effects
				(font
					(size 1.27 0.9652)
					(thickness 0.000001)
				)
				(justify left mirror)
			)
		)
		(property "Device Type" "REST4024"
			(at 0.148158 1.3462 270)
			(unlocked yes)
			(layer "B.Fab")
			(hide yes)
			(effects
				(font
					(size 1.27 0.9652)
					(thickness 0.000001)
				)
				(justify left mirror)
			)
		)
		(duplicate_pad_numbers_are_jumpers no)
		(fp_poly
			(pts
				(xy -0.635 1.0668) (xy -0.635 -1.0668) (xy 0.635 -1.0668) (xy 0.635 1.0668)
			)
			(stroke
				(width 0)
				(type default)
			)
			(fill no)
			(layer "B.CrtYd")
		)
		(fp_line
			(start -0.254 -0.508)
			(end -0.254 0.508)
			(stroke
				(width 0.0254)
				(type default)
			)
			(layer "B.Fab")
		)
		(fp_line
			(start -0.254 0.508)
			(end 0.254 0.508)
			(stroke
				(width 0.0254)
				(type default)
			)
			(layer "B.Fab")
		)
		(fp_line
			(start 0.254 -0.508)
			(end -0.254 -0.508)
			(stroke
				(width 0.0254)
				(type default)
			)
			(layer "B.Fab")
		)
		(fp_line
			(start 0.254 0.508)
			(end 0.254 -0.508)
			(stroke
				(width 0.0254)
				(type default)
			)
			(layer "B.Fab")
		)
		(pad "1" smd rect
			(at 0 -0.4191 180)
			(size 0.508 0.5334)
			(layers "B.Cu" "B.Mask" "B.Paste")
			(net "NWK0_I2C_SDA")
		)
		(pad "2" smd rect
			(at 0 0.4191 180)
			(size 0.508 0.5334)
			(layers "B.Cu" "B.Mask" "B.Paste")
			(net "EXT_3.3V")
		)
		(zone
			(layer "B.Cu")
			(hatch none 0.5)
			(connect_pads
				(clearance 0)
			)
			(min_thickness 0.25)
			(keepout
				(tracks not_allowed)
				(vias allowed)
				(pads allowed)
				(copperpour not_allowed)
				(footprints allowed)
			)
			(placement
				(enabled no)
				(sheetname "")
			)
			(fill
				(thermal_gap 0.5)
				(thermal_bridge_width 0.5)
				(island_removal_mode 0)
			)
			(polygon
				(pts
					(xy 0.5842 17.4244) (xy 0.5842 17.4752) (xy 0.635 17.4752) (xy 0.635 17.4244)
				)
			)
		)
	)
	(footprint ""
		(layer "B.Cu")
		(at 5.08 4.699 90)
		(property "Reference" "R276"
			(at 0 0 90)
			(layer "B.SilkS")
			(hide yes)
			(effects
				(font
					(size 1.27 1.27)
				)
				(justify mirror)
			)
		)
		(property "Value" "240"
			(at 0.148158 1.3462 0)
			(unlocked yes)
			(layer "B.Fab")
			(hide yes)
			(effects
				(font
					(size 1.27 0.9652)
					(thickness 0.000001)
				)
				(justify left mirror)
			)
		)
		(property "Device Type" "REST0009"
			(at 0.148158 1.3462 0)
			(unlocked yes)
			(layer "B.Fab")
			(hide yes)
			(effects
				(font
					(size 1.27 0.9652)
					(thickness 0.000001)
				)
				(justify left mirror)
			)
		)
		(duplicate_pad_numbers_are_jumpers no)
		(fp_poly
			(pts
				(xy -0.635 1.0668) (xy -0.635 -1.0668) (xy 0.635 -1.0668) (xy 0.635 1.0668)
			)
			(stroke
				(width 0)
				(type default)
			)
			(fill no)
			(layer "B.CrtYd")
		)
		(fp_line
			(start 0.254 -0.508)
			(end -0.254 -0.508)
			(stroke
				(width 0.0254)
				(type default)
			)
			(layer "B.Fab")
		)
		(fp_line
			(start -0.254 -0.508)
			(end -0.254 0.508)
			(stroke
				(width 0.0254)
				(type default)
			)
			(layer "B.Fab")
		)
		(fp_line
			(start 0.254 0.508)
			(end 0.254 -0.508)
			(stroke
				(width 0.0254)
				(type default)
			)
			(layer "B.Fab")
		)
		(fp_line
			(start -0.254 0.508)
			(end 0.254 0.508)
			(stroke
				(width 0.0254)
				(type default)
			)
			(layer "B.Fab")
		)
		(pad "1" smd rect
			(at 0 -0.4191 270)
			(size 0.508 0.5334)
			(layers "B.Cu" "B.Mask" "B.Paste")
			(net "CPLD_NFP_RST_LED_L")
		)
		(pad "2" smd rect
			(at 0 0.4191 270)
			(size 0.508 0.5334)
			(layers "B.Cu" "B.Mask" "B.Paste")
			(net "9N2152")
		)
		(zone
			(layer "B.Cu")
			(hatch none 0.5)
			(connect_pads
				(clearance 0)
			)
			(min_thickness 0.25)
			(keepout
				(tracks not_allowed)
				(vias allowed)
				(pads allowed)
				(copperpour not_allowed)
				(footprints allowed)
			)
			(placement
				(enabled no)
				(sheetname "")
			)
			(fill
				(thermal_gap 0.5)
				(thermal_bridge_width 0.5)
				(island_removal_mode 0)
			)
			(polygon
				(pts
					(xy 5.0546 4.7244) (xy 5.1054 4.7244) (xy 5.1054 4.6736) (xy 5.0546 4.6736)
				)
			)
		)
	)
	(footprint ""
		(layer "B.Cu")
		(at 61.849 41.91)
		(property "Reference" "C15"
			(at 0.98933 3.683 270)
			(unlocked yes)
			(layer "B.SilkS")
			(effects
				(font
					(size 0.7874 0.5842)
					(thickness 0.127)
				)
				(justify left mirror)
			)
		)
		(property "Value" "22UF"
			(at 0.148158 1.7526 270)
			(unlocked yes)
			(layer "B.Fab")
			(hide yes)
			(effects
				(font
					(size 1.27 0.9652)
					(thickness 0.000001)
				)
				(justify left mirror)
			)
		)
		(property "Device Type" "CAPC0063"
			(at 0.148158 1.7526 270)
			(unlocked yes)
			(layer "B.Fab")
			(hide yes)
			(effects
				(font
					(size 1.27 0.9652)
					(thickness 0.000001)
				)
				(justify left mirror)
			)
		)
		(duplicate_pad_numbers_are_jumpers no)
		(fp_circle
			(center 0 0)
			(end 0.127 0)
			(stroke
				(width 0.2032)
				(type default)
			)
			(fill no)
			(layer "B.SilkS")
		)
		(fp_poly
			(pts
				(xy -0.7874 -1.6637) (xy 0.7874 -1.6637) (xy 0.7874 1.6637) (xy -0.7874 1.6637)
			)
			(stroke
				(width 0)
				(type default)
			)
			(fill no)
			(layer "B.CrtYd")
		)
		(fp_line
			(start -0.4064 -0.7874)
			(end -0.4064 0.8128)
			(stroke
				(width 0.0254)
				(type default)
			)
			(layer "B.Fab")
		)
		(fp_line
			(start -0.4064 0.8128)
			(end 0.4064 0.8128)
			(stroke
				(width 0.0254)
				(type default)
			)
			(layer "B.Fab")
		)
		(fp_line
			(start 0.4064 -0.7874)
			(end -0.4064 -0.7874)
			(stroke
				(width 0.0254)
				(type default)
			)
			(layer "B.Fab")
		)
		(fp_line
			(start 0.4064 0.8128)
			(end 0.4064 -0.7874)
			(stroke
				(width 0.0254)
				(type default)
			)
			(layer "B.Fab")
		)
		(pad "1" smd rect
			(at 0 -0.8001 180)
			(size 0.8636 0.9652)
			(layers "B.Cu" "B.Mask" "B.Paste")
			(net "VDD_CORE")
		)
		(pad "2" smd rect
			(at 0 0.8001 180)
			(size 0.8636 0.9652)
			(layers "B.Cu" "B.Mask" "B.Paste")
			(net "GND")
		)
		(zone
			(layer "B.Cu")
			(hatch none 0.5)
			(connect_pads
				(clearance 0)
			)
			(min_thickness 0.25)
			(keepout
				(tracks not_allowed)
				(vias allowed)
				(pads allowed)
				(copperpour not_allowed)
				(footprints allowed)
			)
			(placement
				(enabled no)
				(sheetname "")
			)
			(fill
				(thermal_gap 0.5)
				(thermal_bridge_width 0.5)
				(island_removal_mode 0)
			)
			(polygon
				(pts
					(xy 61.9125 41.656) (xy 61.7855 41.656) (xy 61.7855 42.164) (xy 61.9125 42.164)
				)
			)
		)
	)
)
